(kicad_pcb
	(version 20241229)
	(generator "pcbnew")
	(generator_version "9.0")
	(general
		(thickness 1.6642)
		(legacy_teardrops no)
	)
	(paper "A3")
	(title_block
		(title "PolarFire SoM")
		(date "2025-07-22")
		(rev "1.1.4")
		(company "Antmicro Ltd")
		(comment 1 "www.antmicro.com")
		(comment 9 "footprints 447-450 of 470")
	)
	(layers
		(0 "F.Cu" mixed)
		(4 "In1.Cu" power)
		(6 "In2.Cu" signal)
		(8 "In3.Cu" power)
		(10 "In4.Cu" signal)
		(12 "In5.Cu" power)
		(14 "In6.Cu" power)
		(16 "In7.Cu" signal)
		(18 "In8.Cu" power)
		(20 "In9.Cu" signal)
		(22 "In10.Cu" power)
		(24 "In11.Cu" signal)
		(26 "In12.Cu" signal)
		(2 "B.Cu" mixed)
		(9 "F.Adhes" user "F.Adhesive")
		(11 "B.Adhes" user "B.Adhesive")
		(13 "F.Paste" user)
		(15 "B.Paste" user)
		(5 "F.SilkS" user "F.Silkscreen")
		(7 "B.SilkS" user "B.Silkscreen")
		(1 "F.Mask" user)
		(3 "B.Mask" user)
		(17 "Dwgs.User" user "User.Drawings")
		(19 "Cmts.User" user "User.Comments")
		(21 "Eco1.User" user "User.Eco1")
		(23 "Eco2.User" user "User.Eco2")
		(25 "Edge.Cuts" user)
		(27 "Margin" user)
		(31 "F.CrtYd" user "F.Courtyard")
		(29 "B.CrtYd" user "B.Courtyard")
		(35 "F.Fab" user)
		(33 "B.Fab" user)
	)
	(footprint "antmicro-footprints:R_0402_1005Metric"
		(layer "B.Cu")
		(at 226.68 131.6)
		(descr "Resistor SMD 0402")
		(tags "resistor SMD 0402")
		(property "Reference" "R82"
			(at 2.92 0.4 180)
			(layer "B.SilkS")
			(effects
				(font
					(size 0.7 0.7)
					(thickness 0.15)
				)
				(justify left bottom mirror)
			)
		)
		(property "Value" "R_100k_0402"
			(at -1.011843 -1.772047 180)
			(layer "B.Fab")
			(hide yes)
			(effects
				(font
					(size 0.7 0.7)
					(thickness 0.15)
				)
				(justify left bottom mirror)
			)
		)
		(property "Datasheet" "https://www.bourns.com/docs/product-datasheets/cr.pdf"
			(at 0 0 0)
			(layer "F.Fab")
			(hide yes)
			(effects
				(font
					(size 1.27 1.27)
					(thickness 0.15)
				)
			)
		)
		(property "Description" "SMD Chip Resistor, 100 kohm, ± 1%, 62.5 mW, 0402 [1005 Metric], Thick Film, General Purpose"
			(at 0 0 0)
			(layer "F.Fab")
			(hide yes)
			(effects
				(font
					(size 1.27 1.27)
					(thickness 0.15)
				)
			)
		)
		(property "Author" "Antmicro"
			(at 0 0 0)
			(layer "B.Fab")
			(hide yes)
			(effects
				(font
					(size 1 1)
					(thickness 0.15)
				)
				(justify mirror)
			)
		)
		(property "License" "Apache-2.0"
			(at 0 0 0)
			(layer "B.Fab")
			(hide yes)
			(effects
				(font
					(size 1 1)
					(thickness 0.15)
				)
				(justify mirror)
			)
		)
		(property "MPN" "CR0402-FX-1003GLF"
			(at 0 0 0)
			(layer "B.Fab")
			(hide yes)
			(effects
				(font
					(size 1 1)
					(thickness 0.15)
				)
				(justify mirror)
			)
		)
		(property "Manufacturer" "Bourns"
			(at 0 0 0)
			(layer "B.Fab")
			(hide yes)
			(effects
				(font
					(size 1 1)
					(thickness 0.15)
				)
				(justify mirror)
			)
		)
		(property "Public" ""
			(at 0 0 0)
			(layer "B.Fab")
			(hide yes)
			(effects
				(font
					(size 1 1)
					(thickness 0.15)
				)
				(justify mirror)
			)
		)
		(property "Tolerance" "1%"
			(at 0 0 0)
			(layer "B.Fab")
			(hide yes)
			(effects
				(font
					(size 1 1)
					(thickness 0.15)
				)
				(justify mirror)
			)
		)
		(property "Val" "100k"
			(at 0 0 0)
			(layer "B.Fab")
			(hide yes)
			(effects
				(font
					(size 1 1)
					(thickness 0.15)
				)
				(justify mirror)
			)
		)
		(sheetname "/FPGA GPIO/")
		(sheetfile "fpga-gpio.kicad_sch")
		(attr smd)
		(fp_rect
			(start -0.925 0.47)
			(end 0.925 -0.47)
			(stroke
				(width 0.05)
				(type default)
			)
			(fill no)
			(layer "B.CrtYd")
		)
		(fp_rect
			(start -0.5 0.25)
			(end 0.5 -0.25)
			(stroke
				(width 0.15)
				(type solid)
			)
			(fill no)
			(layer "B.Fab")
		)
		(fp_text user "Author: Antmicro"
			(at -0.95 -4.169 180)
			(layer "B.Fab")
			(effects
				(font
					(size 0.7 0.7)
					(thickness 0.15)
				)
				(justify left bottom mirror)
			)
		)
		(fp_text user "License: Apache-2.0"
			(at -0.95 -5.169 180)
			(layer "B.Fab")
			(effects
				(font
					(size 0.7 0.7)
					(thickness 0.15)
				)
				(justify left bottom mirror)
			)
		)
		(fp_text user "${REFERENCE}"
			(at -0.95 -3.168 180)
			(layer "B.Fab")
			(effects
				(font
					(size 0.7 0.7)
					(thickness 0.15)
				)
				(justify left bottom mirror)
			)
		)
		(pad "1" smd roundrect
			(at -0.48 0)
			(size 0.59 0.64)
			(layers "B.Cu" "B.Mask" "B.Paste")
			(roundrect_rratio 0.25)
			(net 417 "GND")
			(pintype "passive")
		)
		(pad "2" smd roundrect
			(at 0.48 0)
			(size 0.59 0.64)
			(layers "B.Cu" "B.Mask" "B.Paste")
			(roundrect_rratio 0.25)
			(net 342 "/FPGA GPIO/USER_LED_R")
			(pintype "passive")
		)
	)
	(footprint "antmicro-footprints:C_0402_1005Metric"
		(layer "B.Cu")
		(at 216.361 123.254 -90)
		(descr "Capacitor SMD 0402")
		(tags "capacitor SMD 0402")
		(property "Reference" "C253"
			(at 1.886 -0.689 90)
			(layer "B.SilkS")
			(effects
				(font
					(size 0.7 0.7)
					(thickness 0.15)
				)
				(justify left bottom mirror)
			)
		)
		(property "Value" "C_1u_0402"
			(at -1.022927 -2.155213 90)
			(layer "B.Fab")
			(hide yes)
			(effects
				(font
					(size 0.7 0.7)
					(thickness 0.15)
				)
				(justify left bottom mirror)
			)
		)
		(property "Datasheet" "https://product.tdk.com/en/search/capacitor/ceramic/mlcc/info?part_no=C1005X6S1A105K050BC"
			(at 0 0 270)
			(layer "F.Fab")
			(hide yes)
			(effects
				(font
					(size 1.27 1.27)
					(thickness 0.15)
				)
			)
		)
		(property "Description" "SMD Multilayer Ceramic Capacitor, 1 µF, 10 V, 0402 [1005 Metric], ± 10%, X6S, C"
			(at 0 0 270)
			(layer "F.Fab")
			(hide yes)
			(effects
				(font
					(size 1.27 1.27)
					(thickness 0.15)
				)
			)
		)
		(property "Author" "Antmicro"
			(at 93.107 339.615 0)
			(layer "B.Fab")
			(hide yes)
			(effects
				(font
					(size 1 1)
					(thickness 0.15)
				)
				(justify mirror)
			)
		)
		(property "Dielectric" ""
			(at 93.107 339.615 0)
			(layer "B.Fab")
			(hide yes)
			(effects
				(font
					(size 1 1)
					(thickness 0.15)
				)
				(justify mirror)
			)
		)
		(property "License" "Apache-2.0"
			(at 93.107 339.615 0)
			(layer "B.Fab")
			(hide yes)
			(effects
				(font
					(size 1 1)
					(thickness 0.15)
				)
				(justify mirror)
			)
		)
		(property "MPN" "C1005X6S1A105K050BC"
			(at 93.107 339.615 0)
			(layer "B.Fab")
			(hide yes)
			(effects
				(font
					(size 1 1)
					(thickness 0.15)
				)
				(justify mirror)
			)
		)
		(property "Manufacturer" "TDK"
			(at 93.107 339.615 0)
			(layer "B.Fab")
			(hide yes)
			(effects
				(font
					(size 1 1)
					(thickness 0.15)
				)
				(justify mirror)
			)
		)
		(property "Public" ""
			(at 93.107 339.615 0)
			(layer "B.Fab")
			(hide yes)
			(effects
				(font
					(size 1 1)
					(thickness 0.15)
				)
				(justify mirror)
			)
		)
		(property "Val" "1u"
			(at 93.107 339.615 0)
			(layer "B.Fab")
			(hide yes)
			(effects
				(font
					(size 1 1)
					(thickness 0.15)
				)
				(justify mirror)
			)
		)
		(property "Voltage" ""
			(at 93.107 339.615 0)
			(layer "B.Fab")
			(hide yes)
			(effects
				(font
					(size 1 1)
					(thickness 0.15)
				)
				(justify mirror)
			)
		)
		(sheetname "/Ethernet/")
		(sheetfile "ethernet.kicad_sch")
		(attr smd)
		(fp_rect
			(start -0.925 0.47)
			(end 0.925 -0.47)
			(stroke
				(width 0.05)
				(type default)
			)
			(fill no)
			(layer "B.CrtYd")
		)
		(fp_line
			(start -0.494 0.25)
			(end 0.504 0.25)
			(stroke
				(width 0.15)
				(type solid)
			)
			(layer "B.Fab")
		)
		(fp_line
			(start 0.504 0.25)
			(end 0.504 -0.248)
			(stroke
				(width 0.15)
				(type solid)
			)
			(layer "B.Fab")
		)
		(fp_line
			(start -0.494 -0.248)
			(end -0.494 0.25)
			(stroke
				(width 0.15)
				(type solid)
			)
			(layer "B.Fab")
		)
		(fp_line
			(start 0.504 -0.248)
			(end -0.494 -0.248)
			(stroke
				(width 0.15)
				(type solid)
			)
			(layer "B.Fab")
		)
		(fp_text user "Author: Antmicro"
			(at -0.939 -3.399 90)
			(layer "B.Fab")
			(effects
				(font
					(size 0.7 0.7)
					(thickness 0.15)
				)
				(justify left bottom mirror)
			)
		)
		(fp_text user "License: Apache-2.0"
			(at -0.939 -5.799 90)
			(layer "B.Fab")
			(effects
				(font
					(size 0.7 0.7)
					(thickness 0.15)
				)
				(justify left bottom mirror)
			)
		)
		(fp_text user "${REFERENCE}"
			(at -0.939 -4.599 90)
			(layer "B.Fab")
			(effects
				(font
					(size 0.7 0.7)
					(thickness 0.15)
				)
				(justify left bottom mirror)
			)
		)
		(pad "1" smd roundrect
			(at -0.48 0 270)
			(size 0.59 0.64)
			(layers "B.Cu" "B.Mask" "B.Paste")
			(roundrect_rratio 0.25)
			(net 417 "GND")
			(pintype "passive")
		)
		(pad "2" smd roundrect
			(at 0.48 0 270)
			(size 0.59 0.64)
			(layers "B.Cu" "B.Mask" "B.Paste")
			(roundrect_rratio 0.25)
			(net 47 "+1V05")
			(pintype "passive")
		)
	)
	(footprint "antmicro-footprints:C_0402_1005Metric"
		(layer "B.Cu")
		(at 195.89 131.1 -90)
		(descr "Capacitor SMD 0402")
		(tags "capacitor SMD 0402")
		(property "Reference" "C38"
			(at 0.85 0.49 0)
			(layer "B.SilkS")
			(effects
				(font
					(size 0.7 0.7)
					(thickness 0.15)
				)
				(justify left bottom mirror)
			)
		)
		(property "Value" "C_4n7_0402"
			(at -1.022927 -2.155213 90)
			(layer "B.Fab")
			(hide yes)
			(effects
				(font
					(size 0.7 0.7)
					(thickness 0.15)
				)
				(justify left bottom mirror)
			)
		)
		(property "Datasheet" "https://product.tdk.com/en/search/capacitor/ceramic/mlcc/info?part_no=CGA2B3X7S2A472K050BB"
			(at 0 0 270)
			(layer "F.Fab")
			(hide yes)
			(effects
				(font
					(size 1.27 1.27)
					(thickness 0.15)
				)
			)
		)
		(property "Description" "SMD Multilayer Ceramic Capacitor, 4700 pF, 100 V, 0402 [1005 Metric], ± 10%, X7S, CGA"
			(at 0 0 270)
			(layer "F.Fab")
			(hide yes)
			(effects
				(font
					(size 1.27 1.27)
					(thickness 0.15)
				)
			)
		)
		(property "Author" "Antmicro"
			(at 64.79 326.99 0)
			(layer "B.Fab")
			(hide yes)
			(effects
				(font
					(size 1 1)
					(thickness 0.15)
				)
				(justify mirror)
			)
		)
		(property "Dielectric" "X7R"
			(at 64.79 326.99 0)
			(layer "B.Fab")
			(hide yes)
			(effects
				(font
					(size 1 1)
					(thickness 0.15)
				)
				(justify mirror)
			)
		)
		(property "License" "Apache-2.0"
			(at 64.79 326.99 0)
			(layer "B.Fab")
			(hide yes)
			(effects
				(font
					(size 1 1)
					(thickness 0.15)
				)
				(justify mirror)
			)
		)
		(property "MPN" "CGA2B3X7S2A472K050BB"
			(at 64.79 326.99 0)
			(layer "B.Fab")
			(hide yes)
			(effects
				(font
					(size 1 1)
					(thickness 0.15)
				)
				(justify mirror)
			)
		)
		(property "Manufacturer" "TDK"
			(at 64.79 326.99 0)
			(layer "B.Fab")
			(hide yes)
			(effects
				(font
					(size 1 1)
					(thickness 0.15)
				)
				(justify mirror)
			)
		)
		(property "Public" ""
			(at 64.79 326.99 0)
			(layer "B.Fab")
			(hide yes)
			(effects
				(font
					(size 1 1)
					(thickness 0.15)
				)
				(justify mirror)
			)
		)
		(property "Val" "4n7"
			(at 64.79 326.99 0)
			(layer "B.Fab")
			(hide yes)
			(effects
				(font
					(size 1 1)
					(thickness 0.15)
				)
				(justify mirror)
			)
		)
		(property "Voltage" "25V"
			(at 64.79 326.99 0)
			(layer "B.Fab")
			(hide yes)
			(effects
				(font
					(size 1 1)
					(thickness 0.15)
				)
				(justify mirror)
			)
		)
		(sheetname "/FPGA Supply/")
		(sheetfile "fpga-supply.kicad_sch")
		(attr smd)
		(fp_rect
			(start -0.925 0.47)
			(end 0.925 -0.47)
			(stroke
				(width 0.05)
				(type default)
			)
			(fill no)
			(layer "B.CrtYd")
		)
		(fp_line
			(start -0.494 0.25)
			(end 0.504 0.25)
			(stroke
				(width 0.15)
				(type solid)
			)
			(layer "B.Fab")
		)
		(fp_line
			(start 0.504 0.25)
			(end 0.504 -0.248)
			(stroke
				(width 0.15)
				(type solid)
			)
			(layer "B.Fab")
		)
		(fp_line
			(start -0.494 -0.248)
			(end -0.494 0.25)
			(stroke
				(width 0.15)
				(type solid)
			)
			(layer "B.Fab")
		)
		(fp_line
			(start 0.504 -0.248)
			(end -0.494 -0.248)
			(stroke
				(width 0.15)
				(type solid)
			)
			(layer "B.Fab")
		)
		(fp_text user "${REFERENCE}"
			(at -0.939 -4.599 90)
			(layer "B.Fab")
			(effects
				(font
					(size 0.7 0.7)
					(thickness 0.15)
				)
				(justify left bottom mirror)
			)
		)
		(fp_text user "License: Apache-2.0"
			(at -0.939 -5.799 90)
			(layer "B.Fab")
			(effects
				(font
					(size 0.7 0.7)
					(thickness 0.15)
				)
				(justify left bottom mirror)
			)
		)
		(fp_text user "Author: Antmicro"
			(at -0.939 -3.399 90)
			(layer "B.Fab")
			(effects
				(font
					(size 0.7 0.7)
					(thickness 0.15)
				)
				(justify left bottom mirror)
			)
		)
		(pad "1" smd roundrect
			(at -0.48 0 270)
			(size 0.59 0.64)
			(layers "B.Cu" "B.Mask" "B.Paste")
			(roundrect_rratio 0.25)
			(net 417 "GND")
			(pintype "passive")
		)
		(pad "2" smd roundrect
			(at 0.48 0 270)
			(size 0.59 0.64)
			(layers "B.Cu" "B.Mask" "B.Paste")
			(roundrect_rratio 0.25)
			(net 48 "+1V8")
			(pintype "passive")
		)
	)
	(footprint "antmicro-footprints:R_0402_1005Metric"
		(layer "B.Cu")
		(at 217.94 125.67 -135)
		(descr "Resistor SMD 0402")
		(tags "resistor SMD 0402")
		(property "Reference" "R102"
			(at 1.647559 -1.407142 225)
			(layer "B.SilkS")
			(effects
				(font
					(size 0.7 0.7)
					(thickness 0.15)
				)
				(justify right bottom mirror)
			)
		)
		(property "Value" "R_10k_0402"
			(at -1.011843 -1.772046 45)
			(layer "B.Fab")
			(hide yes)
			(effects
				(font
					(size 0.7 0.7)
					(thickness 0.15)
				)
				(justify left bottom mirror)
			)
		)
		(property "Datasheet" "https://www.bourns.com/docs/product-datasheets/cr.pdf"
			(at 0 0 225)
			(layer "F.Fab")
			(hide yes)
			(effects
				(font
					(size 1.27 1.27)
					(thickness 0.15)
				)
			)
		)
		(property "Description" "SMD Chip Resistor, 10 kohm, ± 1%, 62.5 mW, 0402 [1005 Metric], Thick Film, General Purpose"
			(at 0 0 225)
			(layer "F.Fab")
			(hide yes)
			(effects
				(font
					(size 1.27 1.27)
					(thickness 0.15)
				)
			)
		)
		(property "Author" "Antmicro"
			(at 283.184743 368.638961 0)
			(layer "B.Fab")
			(hide yes)
			(effects
				(font
					(size 1 1)
					(thickness 0.15)
				)
				(justify mirror)
			)
		)
		(property "License" "Apache-2.0"
			(at 283.184743 368.638961 0)
			(layer "B.Fab")
			(hide yes)
			(effects
				(font
					(size 1 1)
					(thickness 0.15)
				)
				(justify mirror)
			)
		)
		(property "MPN" "CR0402-FX-1002GLF"
			(at 283.184743 368.638961 0)
			(layer "B.Fab")
			(hide yes)
			(effects
				(font
					(size 1 1)
					(thickness 0.15)
				)
				(justify mirror)
			)
		)
		(property "Manufacturer" "Bourns"
			(at 283.184743 368.638961 0)
			(layer "B.Fab")
			(hide yes)
			(effects
				(font
					(size 1 1)
					(thickness 0.15)
				)
				(justify mirror)
			)
		)
		(property "Public" ""
			(at 283.184743 368.638961 0)
			(layer "B.Fab")
			(hide yes)
			(effects
				(font
					(size 1 1)
					(thickness 0.15)
				)
				(justify mirror)
			)
		)
		(property "Tolerance" "1%"
			(at 283.184743 368.638961 0)
			(layer "B.Fab")
			(hide yes)
			(effects
				(font
					(size 1 1)
					(thickness 0.15)
				)
				(justify mirror)
			)
		)
		(property "Val" "10k"
			(at 283.184743 368.638961 0)
			(layer "B.Fab")
			(hide yes)
			(effects
				(font
					(size 1 1)
					(thickness 0.15)
				)
				(justify mirror)
			)
		)
		(sheetname "/Ethernet/")
		(sheetfile "ethernet.kicad_sch")
		(attr smd)
		(fp_poly
			(pts
				(xy -0.925 0.47) (xy 0.925 0.47) (xy 0.925 -0.47) (xy -0.925 -0.47)
			)
			(stroke
				(width 0.05)
				(type default)
			)
			(fill no)
			(layer "B.CrtYd")
		)
		(fp_poly
			(pts
				(xy -0.5 0.25) (xy 0.5 0.25) (xy 0.5 -0.25) (xy -0.5 -0.25)
			)
			(stroke
				(width 0.15)
				(type solid)
			)
			(fill no)
			(layer "B.Fab")
		)
		(fp_text user "Author: Antmicro"
			(at -0.95 -4.169 45)
			(layer "B.Fab")
			(effects
				(font
					(size 0.7 0.7)
					(thickness 0.15)
				)
				(justify left bottom mirror)
			)
		)
		(fp_text user "License: Apache-2.0"
			(at -0.949999 -5.169 45)
			(layer "B.Fab")
			(effects
				(font
					(size 0.7 0.7)
					(thickness 0.15)
				)
				(justify left bottom mirror)
			)
		)
		(fp_text user "${REFERENCE}"
			(at -0.95 -3.168 45)
			(layer "B.Fab")
			(effects
				(font
					(size 0.7 0.7)
					(thickness 0.15)
				)
				(justify left bottom mirror)
			)
		)
		(pad "1" smd roundrect
			(at -0.48 0 225)
			(size 0.59 0.64)
			(layers "B.Cu" "B.Mask" "B.Paste")
			(roundrect_rratio 0.25)
			(net 617 "/Ethernet/LED0")
			(pintype "passive")
		)
		(pad "2" smd roundrect
			(at 0.48 0 225)
			(size 0.59 0.64)
			(layers "B.Cu" "B.Mask" "B.Paste")
			(roundrect_rratio 0.25)
			(net 50 "+3V3")
			(pintype "passive")
		)
	)
)
